# T6G (Grand Teton) — schematic netlist excerpt (pin names and nets, part order shuffled) for the footprints in the layout excerpt that follows; sources: Cadence DE-HDL packaged netlist, KiCad conversion of 04192023_DAF0TMB3IC0_F0TG_MB_C_brd_V02_OCP.brd

C959  Q_CAP_DIFFBUS  DIFF BUS_0.22UF 6.3V 20% X6S  pkg C0201  page 63 : \1\ = P5E_CPU0_P1_TX_C_DP<3> ; \2\ = P5E_CPU0_P1_TX_DP<3>
R3201  Q_RES  0 5% CHIP  pkg 0402LF  page 55 : A = CLK_100M_CPU1_CLK05_R_DN ; B = CLK_100M_CPU1_CLK05_DN
R6268  Q_RES  0 5% CHIP  pkg 0402LF  page 178 : A = USB_HUB2_TI_USB_SSRXM_DN4_MRP_VDD12 ; B = P1V2_CPU0_USB2_DVDD12

(kicad_pcb
	(version 20260206)
	(generator "pcbnew")
	(generator_version "10.0")
	(general
		(thickness 1.6)
		(legacy_teardrops no)
	)
	(paper "A4")
	(title_block
		(title "04192023_DAF0TMB3IC0_F0TG_MB_C_brd_V02_OCP.brd")
		(comment 1 "Grand Teton / footprints 2760-2762 of 8354")
	)
	(layers
		(0 "F.Cu" signal "TOP")
		(4 "In1.Cu" signal "GND")
		(6 "In2.Cu" signal "IN1")
		(8 "In3.Cu" signal "GND1")
		(10 "In4.Cu" signal "IN2")
		(12 "In5.Cu" signal "GND2")
		(14 "In6.Cu" signal "IN3")
		(16 "In7.Cu" signal "GND3")
		(18 "In8.Cu" signal "VCC")
		(20 "In9.Cu" signal "VCC1")
		(22 "In10.Cu" signal "GND4")
		(24 "In11.Cu" signal "IN4")
		(26 "In12.Cu" signal "GND5")
		(28 "In13.Cu" signal "IN5")
		(30 "In14.Cu" signal "GND6")
		(32 "In15.Cu" signal "IN6")
		(34 "In16.Cu" signal "GND7")
		(2 "B.Cu" signal "BOTTOM")
		(9 "F.Adhes" user "F.Adhesive")
		(11 "B.Adhes" user "B.Adhesive")
		(13 "F.Paste" user "Package Geometry/Pastemask Top")
		(15 "B.Paste" user "Package Geometry/Pastemask Bottom")
		(5 "F.SilkS" user "Ref Des/Silkscreen Top")
		(7 "B.SilkS" user "Ref Des/Silkscreen Bottom")
		(1 "F.Mask" user "Board Geometry/Soldermask Top")
		(3 "B.Mask" user "Board Geometry/Soldermask Bottom")
		(17 "Dwgs.User" user "User.Drawings")
		(19 "Cmts.User" user "User.Comments")
		(21 "Eco1.User" user "User.Eco1")
		(23 "Eco2.User" user "User.Eco2")
		(25 "Edge.Cuts" user "Board Geometry/Outline")
		(27 "Margin" user)
		(31 "F.CrtYd" user "Package Geometry/Place Bound Top")
		(29 "B.CrtYd" user "Package Geometry/Place Bound Bottom")
		(35 "F.Fab" user "Ref Des/Assembly Top")
		(33 "B.Fab" user "Ref Des/Assembly Bottom")
	)
	(footprint ""
		(layer "F.Cu")
		(at 152.270206 -191.35471 -90)
		(property "Reference" "R3201"
			(at 0 0 270)
			(layer "F.SilkS")
			(hide yes)
			(effects
				(font
					(size 1.27 1.27)
				)
			)
		)
		(property "Value" ""
			(at 0 0 270)
			(layer "F.Fab")
			(effects
				(font
					(size 1.27 1.27)
				)
			)
		)
		(duplicate_pad_numbers_are_jumpers no)
		(fp_line
			(start 0.42291 0.4064)
			(end -0.41529 0.4064)
			(stroke
				(width 0.1524)
				(type default)
			)
			(layer "F.SilkS")
		)
		(fp_line
			(start -0.7874 -0.002794)
			(end -0.7874 -0.4064)
			(stroke
				(width 0.1524)
				(type default)
			)
			(layer "F.SilkS")
		)
		(fp_line
			(start -0.7874 -0.4064)
			(end 0.7874 -0.4064)
			(stroke
				(width 0.1524)
				(type default)
			)
			(layer "F.SilkS")
		)
		(fp_line
			(start 0.7874 -0.4064)
			(end 0.7874 -0.002794)
			(stroke
				(width 0.1524)
				(type default)
			)
			(layer "F.SilkS")
		)
		(fp_line
			(start -0.67945 0.3048)
			(end -0.67945 -0.305054)
			(stroke
				(width 0.1)
				(type default)
			)
			(layer "F.Fab")
		)
		(fp_line
			(start -0.12065 0.3048)
			(end -0.67945 0.3048)
			(stroke
				(width 0.1)
				(type default)
			)
			(layer "F.Fab")
		)
		(fp_line
			(start 0.120396 0.3048)
			(end 0.120396 0.2794)
			(stroke
				(width 0.1)
				(type default)
			)
			(layer "F.Fab")
		)
		(fp_line
			(start 0.67945 0.3048)
			(end 0.120396 0.3048)
			(stroke
				(width 0.1)
				(type default)
			)
			(layer "F.Fab")
		)
		(fp_line
			(start -0.12065 0.2794)
			(end -0.12065 0.3048)
			(stroke
				(width 0.1)
				(type default)
			)
			(layer "F.Fab")
		)
		(fp_line
			(start 0.120396 0.2794)
			(end -0.12065 0.2794)
			(stroke
				(width 0.1)
				(type default)
			)
			(layer "F.Fab")
		)
		(fp_line
			(start -0.12065 -0.2794)
			(end 0.12065 -0.2794)
			(stroke
				(width 0.1)
				(type default)
			)
			(layer "F.Fab")
		)
		(fp_line
			(start 0.12065 -0.2794)
			(end 0.12065 -0.3048)
			(stroke
				(width 0.1)
				(type default)
			)
			(layer "F.Fab")
		)
		(fp_line
			(start 0.12065 -0.3048)
			(end 0.67945 -0.3048)
			(stroke
				(width 0.1)
				(type default)
			)
			(layer "F.Fab")
		)
		(fp_line
			(start 0.67945 -0.3048)
			(end 0.67945 0.3048)
			(stroke
				(width 0.1)
				(type default)
			)
			(layer "F.Fab")
		)
		(fp_line
			(start -0.67945 -0.305054)
			(end -0.12065 -0.305054)
			(stroke
				(width 0.1)
				(type default)
			)
			(layer "F.Fab")
		)
		(fp_line
			(start -0.12065 -0.305054)
			(end -0.12065 -0.2794)
			(stroke
				(width 0.1)
				(type default)
			)
			(layer "F.Fab")
		)
		(pad "1" smd circle
			(at -0.40005 0 270)
			(size 0 0)
			(layers "F.Cu" "F.Mask" "F.Paste")
			(net "CLK_100M_CPU1_CLK05_R_DN")
		)
		(pad "2" smd circle
			(at 0.40005 0 270)
			(size 0 0)
			(layers "F.Cu" "F.Mask" "F.Paste")
			(net "CLK_100M_CPU1_CLK05_DN")
		)
	)
	(footprint ""
		(layer "F.Cu")
		(at 120.69826 -30.389576)
		(property "Reference" "R6268"
			(at 0 0 0)
			(layer "F.SilkS")
			(hide yes)
			(effects
				(font
					(size 1.27 1.27)
				)
			)
		)
		(property "Value" ""
			(at 0 0 0)
			(layer "F.Fab")
			(effects
				(font
					(size 1.27 1.27)
				)
			)
		)
		(duplicate_pad_numbers_are_jumpers no)
		(fp_line
			(start -0.7874 -0.4064)
			(end 0.7874 -0.4064)
			(stroke
				(width 0.1524)
				(type default)
			)
			(layer "F.SilkS")
		)
		(fp_line
			(start -0.7874 0.4064)
			(end -0.7874 -0.4064)
			(stroke
				(width 0.1524)
				(type default)
			)
			(layer "F.SilkS")
		)
		(fp_line
			(start 0.7874 -0.4064)
			(end 0.7874 0.4064)
			(stroke
				(width 0.1524)
				(type default)
			)
			(layer "F.SilkS")
		)
		(fp_line
			(start 0.7874 0.4064)
			(end -0.7874 0.4064)
			(stroke
				(width 0.1524)
				(type default)
			)
			(layer "F.SilkS")
		)
		(fp_line
			(start -0.67945 -0.305054)
			(end -0.12065 -0.305054)
			(stroke
				(width 0.1)
				(type default)
			)
			(layer "F.Fab")
		)
		(fp_line
			(start -0.67945 0.3048)
			(end -0.67945 -0.305054)
			(stroke
				(width 0.1)
				(type default)
			)
			(layer "F.Fab")
		)
		(fp_line
			(start -0.12065 -0.305054)
			(end -0.12065 -0.2794)
			(stroke
				(width 0.1)
				(type default)
			)
			(layer "F.Fab")
		)
		(fp_line
			(start -0.12065 -0.2794)
			(end 0.12065 -0.2794)
			(stroke
				(width 0.1)
				(type default)
			)
			(layer "F.Fab")
		)
		(fp_line
			(start -0.12065 0.2794)
			(end -0.12065 0.3048)
			(stroke
				(width 0.1)
				(type default)
			)
			(layer "F.Fab")
		)
		(fp_line
			(start -0.12065 0.3048)
			(end -0.67945 0.3048)
			(stroke
				(width 0.1)
				(type default)
			)
			(layer "F.Fab")
		)
		(fp_line
			(start 0.120396 0.2794)
			(end -0.12065 0.2794)
			(stroke
				(width 0.1)
				(type default)
			)
			(layer "F.Fab")
		)
		(fp_line
			(start 0.120396 0.3048)
			(end 0.120396 0.2794)
			(stroke
				(width 0.1)
				(type default)
			)
			(layer "F.Fab")
		)
		(fp_line
			(start 0.12065 -0.3048)
			(end 0.67945 -0.3048)
			(stroke
				(width 0.1)
				(type default)
			)
			(layer "F.Fab")
		)
		(fp_line
			(start 0.12065 -0.2794)
			(end 0.12065 -0.3048)
			(stroke
				(width 0.1)
				(type default)
			)
			(layer "F.Fab")
		)
		(fp_line
			(start 0.67945 -0.3048)
			(end 0.67945 0.3048)
			(stroke
				(width 0.1)
				(type default)
			)
			(layer "F.Fab")
		)
		(fp_line
			(start 0.67945 0.3048)
			(end 0.120396 0.3048)
			(stroke
				(width 0.1)
				(type default)
			)
			(layer "F.Fab")
		)
		(pad "1" smd circle
			(at -0.40005 0)
			(size 0 0)
			(layers "F.Cu" "F.Mask" "F.Paste")
			(net "USB_HUB2_TI_USB_SSRXM_DN4_MRP_VDD12")
		)
		(pad "2" smd circle
			(at 0.40005 0)
			(size 0 0)
			(layers "F.Cu" "F.Mask" "F.Paste")
			(net "P1V2_CPU0_USB2_DVDD12")
		)
	)
	(footprint ""
		(layer "F.Cu")
		(at 333.219044 -378.95403 -90)
		(property "Reference" "C959"
			(at 0 0 270)
			(layer "F.SilkS")
			(hide yes)
			(effects
				(font
					(size 1.27 1.27)
				)
			)
		)
		(property "Value" ""
			(at 0 0 270)
			(layer "F.Fab")
			(effects
				(font
					(size 1.27 1.27)
				)
			)
		)
		(duplicate_pad_numbers_are_jumpers no)
		(fp_line
			(start -0.299974 0.150114)
			(end -0.299974 -0.150114)
			(stroke
				(width 0.1)
				(type default)
			)
			(layer "F.Fab")
		)
		(fp_line
			(start 0.299974 0.150114)
			(end -0.299974 0.150114)
			(stroke
				(width 0.1)
				(type default)
			)
			(layer "F.Fab")
		)
		(fp_line
			(start -0.299974 -0.150114)
			(end 0.299974 -0.150114)
			(stroke
				(width 0.1)
				(type default)
			)
			(layer "F.Fab")
		)
		(fp_line
			(start 0.299974 -0.150114)
			(end 0.299974 0.150114)
			(stroke
				(width 0.1)
				(type default)
			)
			(layer "F.Fab")
		)
		(pad "1" smd rect
			(at -0.2667 0 270)
			(size 0.3048 0.381)
			(layers "F.Cu" "F.Mask" "F.Paste")
			(net "P5E_CPU0_P1_TX_C_DP<3>")
		)
		(pad "2" smd rect
			(at 0.2667 0 270)
			(size 0.3048 0.381)
			(layers "F.Cu" "F.Mask" "F.Paste")
			(net "P5E_CPU0_P1_TX_DP<3>")
		)
	)
)
